(kicad_pcb
	(version 20260206)
	(generator "pcbnew")
	(generator_version "10.0")
	(general
		(thickness 1.6)
		(legacy_teardrops no)
	)
	(paper "A4")
	(title_block
		(title "01162023_DA0F0TEBIF0_F0T_Expander_BD_F_brd_V02_OCP.brd")
		(comment 1 "Grand Teton / footprints 8331-8338 of 9728")
	)
	(layers
		(0 "F.Cu" signal "TOP")
		(4 "In1.Cu" signal "GND")
		(6 "In2.Cu" signal "VCC")
		(8 "In3.Cu" signal "VCC1")
		(10 "In4.Cu" signal "GND1")
		(12 "In5.Cu" signal "IN1")
		(14 "In6.Cu" signal "GND2")
		(16 "In7.Cu" signal "IN2")
		(18 "In8.Cu" signal "GND3")
		(20 "In9.Cu" signal "IN3")
		(22 "In10.Cu" signal "GND4")
		(24 "In11.Cu" signal "IN4")
		(26 "In12.Cu" signal "GND5")
		(28 "In13.Cu" signal "IN5")
		(30 "In14.Cu" signal "GND6")
		(32 "In15.Cu" signal "IN6")
		(34 "In16.Cu" signal "GND7")
		(2 "B.Cu" signal "BOTTOM")
		(9 "F.Adhes" user "F.Adhesive")
		(11 "B.Adhes" user "B.Adhesive")
		(13 "F.Paste" user "Package Geometry/Pastemask Top")
		(15 "B.Paste" user "Package Geometry/Pastemask Bottom")
		(5 "F.SilkS" user "Ref Des/Silkscreen Top")
		(7 "B.SilkS" user "Ref Des/Silkscreen Bottom")
		(1 "F.Mask" user "Board Geometry/Soldermask Top")
		(3 "B.Mask" user "Board Geometry/Soldermask Bottom")
		(17 "Dwgs.User" user "User.Drawings")
		(19 "Cmts.User" user "User.Comments")
		(21 "Eco1.User" user "User.Eco1")
		(23 "Eco2.User" user "User.Eco2")
		(25 "Edge.Cuts" user "Board Geometry/Outline")
		(27 "Margin" user)
		(31 "F.CrtYd" user "Package Geometry/Place Bound Top")
		(29 "B.CrtYd" user "Package Geometry/Place Bound Bottom")
		(35 "F.Fab" user "Ref Des/Assembly Top")
		(33 "B.Fab" user "Ref Des/Assembly Bottom")
	)
	(footprint ""
		(layer "B.Cu")
		(at 229.146354 -224.667064)
		(property "Reference" "R6813"
			(at 0 0 0)
			(layer "B.SilkS")
			(hide yes)
			(effects
				(font
					(size 1.27 1.27)
				)
				(justify mirror)
			)
		)
		(property "Value" ""
			(at 0 0 0)
			(layer "B.Fab")
			(effects
				(font
					(size 1.27 1.27)
				)
				(justify mirror)
			)
		)
		(duplicate_pad_numbers_are_jumpers no)
		(fp_line
			(start -0.7874 -0.4064)
			(end -0.7874 0.4064)
			(stroke
				(width 0.1524)
				(type default)
			)
			(layer "B.SilkS")
		)
		(fp_line
			(start -0.7874 0.4064)
			(end 0.7874 0.4064)
			(stroke
				(width 0.1524)
				(type default)
			)
			(layer "B.SilkS")
		)
		(fp_line
			(start 0.7874 -0.4064)
			(end -0.7874 -0.4064)
			(stroke
				(width 0.1524)
				(type default)
			)
			(layer "B.SilkS")
		)
		(fp_line
			(start 0.7874 0.4064)
			(end 0.7874 -0.4064)
			(stroke
				(width 0.1524)
				(type default)
			)
			(layer "B.SilkS")
		)
		(fp_line
			(start -0.67945 -0.3048)
			(end -0.67945 0.3048)
			(stroke
				(width 0.1)
				(type default)
			)
			(layer "B.Fab")
		)
		(fp_line
			(start -0.67945 0.3048)
			(end -0.120396 0.3048)
			(stroke
				(width 0.1)
				(type default)
			)
			(layer "B.Fab")
		)
		(fp_line
			(start -0.12065 -0.3048)
			(end -0.67945 -0.3048)
			(stroke
				(width 0.1)
				(type default)
			)
			(layer "B.Fab")
		)
		(fp_line
			(start -0.12065 -0.2794)
			(end -0.12065 -0.3048)
			(stroke
				(width 0.1)
				(type default)
			)
			(layer "B.Fab")
		)
		(fp_line
			(start -0.120396 0.2794)
			(end 0.12065 0.2794)
			(stroke
				(width 0.1)
				(type default)
			)
			(layer "B.Fab")
		)
		(fp_line
			(start -0.120396 0.3048)
			(end -0.120396 0.2794)
			(stroke
				(width 0.1)
				(type default)
			)
			(layer "B.Fab")
		)
		(fp_line
			(start 0.12065 -0.305054)
			(end 0.12065 -0.2794)
			(stroke
				(width 0.1)
				(type default)
			)
			(layer "B.Fab")
		)
		(fp_line
			(start 0.12065 -0.2794)
			(end -0.12065 -0.2794)
			(stroke
				(width 0.1)
				(type default)
			)
			(layer "B.Fab")
		)
		(fp_line
			(start 0.12065 0.2794)
			(end 0.12065 0.3048)
			(stroke
				(width 0.1)
				(type default)
			)
			(layer "B.Fab")
		)
		(fp_line
			(start 0.12065 0.3048)
			(end 0.67945 0.3048)
			(stroke
				(width 0.1)
				(type default)
			)
			(layer "B.Fab")
		)
		(fp_line
			(start 0.67945 -0.305054)
			(end 0.12065 -0.305054)
			(stroke
				(width 0.1)
				(type default)
			)
			(layer "B.Fab")
		)
		(fp_line
			(start 0.67945 0.3048)
			(end 0.67945 -0.305054)
			(stroke
				(width 0.1)
				(type default)
			)
			(layer "B.Fab")
		)
		(pad "1" smd circle
			(at 0.40005 0 180)
			(size 0 0)
			(layers "B.Cu" "B.Mask" "B.Paste")
			(net "BOARD_TYPE_0_ADC_R")
		)
		(pad "2" smd circle
			(at -0.40005 0 180)
			(size 0 0)
			(layers "B.Cu" "B.Mask" "B.Paste")
			(net "P3V3_AUX")
		)
	)
	(footprint ""
		(layer "B.Cu")
		(at 107.6325 -137.56132 90)
		(property "Reference" "PC33"
			(at 0 0 90)
			(layer "B.SilkS")
			(hide yes)
			(effects
				(font
					(size 1.27 1.27)
				)
				(justify mirror)
			)
		)
		(property "Value" ""
			(at 0 0 90)
			(layer "B.Fab")
			(effects
				(font
					(size 1.27 1.27)
				)
				(justify mirror)
			)
		)
		(duplicate_pad_numbers_are_jumpers no)
		(fp_line
			(start 1.524 -0.762)
			(end -1.524 -0.762)
			(stroke
				(width 0.1524)
				(type default)
			)
			(layer "B.SilkS")
		)
		(fp_line
			(start -1.524 -0.762)
			(end -1.524 0.762)
			(stroke
				(width 0.1524)
				(type default)
			)
			(layer "B.SilkS")
		)
		(fp_line
			(start 1.524 0.762)
			(end 1.524 -0.762)
			(stroke
				(width 0.1524)
				(type default)
			)
			(layer "B.SilkS")
		)
		(fp_line
			(start -1.524 0.762)
			(end 1.524 0.762)
			(stroke
				(width 0.1524)
				(type default)
			)
			(layer "B.SilkS")
		)
		(fp_line
			(start 1.1049 -0.724916)
			(end 1.1049 0.724916)
			(stroke
				(width 0.1)
				(type default)
			)
			(layer "B.Fab")
		)
		(fp_line
			(start -1.1049 -0.724916)
			(end 1.1049 -0.724916)
			(stroke
				(width 0.1)
				(type default)
			)
			(layer "B.Fab")
		)
		(fp_line
			(start 1.1049 0.724916)
			(end -1.1049 0.724916)
			(stroke
				(width 0.1)
				(type default)
			)
			(layer "B.Fab")
		)
		(fp_line
			(start -1.1049 0.724916)
			(end -1.1049 -0.724916)
			(stroke
				(width 0.1)
				(type default)
			)
			(layer "B.Fab")
		)
		(pad "1" smd rect
			(at 0.889 0 90)
			(size 1.016 1.27)
			(layers "B.Cu" "B.Mask" "B.Paste")
			(net "P3V3_AUX")
		)
		(pad "2" smd rect
			(at -0.889 0 90)
			(size 1.016 1.27)
			(layers "B.Cu" "B.Mask" "B.Paste")
			(net "GND")
		)
	)
	(footprint ""
		(layer "B.Cu")
		(at 25.15997 -220.924374 90)
		(property "Reference" "R3438"
			(at 0 0 90)
			(layer "B.SilkS")
			(hide yes)
			(effects
				(font
					(size 1.27 1.27)
				)
				(justify mirror)
			)
		)
		(property "Value" ""
			(at 0 0 90)
			(layer "B.Fab")
			(effects
				(font
					(size 1.27 1.27)
				)
				(justify mirror)
			)
		)
		(duplicate_pad_numbers_are_jumpers no)
		(fp_line
			(start 0.7874 -0.4064)
			(end -0.7874 -0.4064)
			(stroke
				(width 0.1524)
				(type default)
			)
			(layer "B.SilkS")
		)
		(fp_line
			(start -0.7874 -0.4064)
			(end -0.7874 0.4064)
			(stroke
				(width 0.1524)
				(type default)
			)
			(layer "B.SilkS")
		)
		(fp_line
			(start 0.7874 0.4064)
			(end 0.7874 -0.4064)
			(stroke
				(width 0.1524)
				(type default)
			)
			(layer "B.SilkS")
		)
		(fp_line
			(start -0.7874 0.4064)
			(end 0.7874 0.4064)
			(stroke
				(width 0.1524)
				(type default)
			)
			(layer "B.SilkS")
		)
		(fp_line
			(start 0.67945 -0.305054)
			(end 0.12065 -0.305054)
			(stroke
				(width 0.1)
				(type default)
			)
			(layer "B.Fab")
		)
		(fp_line
			(start 0.12065 -0.305054)
			(end 0.12065 -0.2794)
			(stroke
				(width 0.1)
				(type default)
			)
			(layer "B.Fab")
		)
		(fp_line
			(start -0.12065 -0.3048)
			(end -0.67945 -0.3048)
			(stroke
				(width 0.1)
				(type default)
			)
			(layer "B.Fab")
		)
		(fp_line
			(start -0.67945 -0.3048)
			(end -0.67945 0.3048)
			(stroke
				(width 0.1)
				(type default)
			)
			(layer "B.Fab")
		)
		(fp_line
			(start 0.12065 -0.2794)
			(end -0.12065 -0.2794)
			(stroke
				(width 0.1)
				(type default)
			)
			(layer "B.Fab")
		)
		(fp_line
			(start -0.12065 -0.2794)
			(end -0.12065 -0.3048)
			(stroke
				(width 0.1)
				(type default)
			)
			(layer "B.Fab")
		)
		(fp_line
			(start 0.12065 0.2794)
			(end 0.12065 0.3048)
			(stroke
				(width 0.1)
				(type default)
			)
			(layer "B.Fab")
		)
		(fp_line
			(start -0.120396 0.2794)
			(end 0.12065 0.2794)
			(stroke
				(width 0.1)
				(type default)
			)
			(layer "B.Fab")
		)
		(fp_line
			(start 0.67945 0.3048)
			(end 0.67945 -0.305054)
			(stroke
				(width 0.1)
				(type default)
			)
			(layer "B.Fab")
		)
		(fp_line
			(start 0.12065 0.3048)
			(end 0.67945 0.3048)
			(stroke
				(width 0.1)
				(type default)
			)
			(layer "B.Fab")
		)
		(fp_line
			(start -0.120396 0.3048)
			(end -0.120396 0.2794)
			(stroke
				(width 0.1)
				(type default)
			)
			(layer "B.Fab")
		)
		(fp_line
			(start -0.67945 0.3048)
			(end -0.120396 0.3048)
			(stroke
				(width 0.1)
				(type default)
			)
			(layer "B.Fab")
		)
		(pad "1" smd circle
			(at 0.40005 0 270)
			(size 0 0)
			(layers "B.Cu" "B.Mask" "B.Paste")
			(net "P1V8_PEX")
		)
		(pad "2" smd circle
			(at -0.40005 0 270)
			(size 0 0)
			(layers "B.Cu" "B.Mask" "B.Paste")
			(net "SPI_PEX0_SDIO3_R1")
		)
	)
	(footprint ""
		(layer "B.Cu")
		(at 381.127 -233.68)
		(property "Reference" "C2582"
			(at 0 0 0)
			(layer "B.SilkS")
			(hide yes)
			(effects
				(font
					(size 1.27 1.27)
				)
				(justify mirror)
			)
		)
		(property "Value" ""
			(at 0 0 0)
			(layer "B.Fab")
			(effects
				(font
					(size 1.27 1.27)
				)
				(justify mirror)
			)
		)
		(duplicate_pad_numbers_are_jumpers no)
		(fp_line
			(start -0.7874 -0.4064)
			(end -0.7874 0.4064)
			(stroke
				(width 0.1524)
				(type default)
			)
			(layer "B.SilkS")
		)
		(fp_line
			(start -0.7874 0.4064)
			(end 0.7874 0.4064)
			(stroke
				(width 0.1524)
				(type default)
			)
			(layer "B.SilkS")
		)
		(fp_line
			(start 0.7874 -0.4064)
			(end -0.7874 -0.4064)
			(stroke
				(width 0.1524)
				(type default)
			)
			(layer "B.SilkS")
		)
		(fp_line
			(start 0.7874 0.4064)
			(end 0.7874 -0.4064)
			(stroke
				(width 0.1524)
				(type default)
			)
			(layer "B.SilkS")
		)
		(fp_line
			(start -0.67945 -0.3048)
			(end -0.67945 0.3048)
			(stroke
				(width 0.1)
				(type default)
			)
			(layer "B.Fab")
		)
		(fp_line
			(start -0.67945 0.3048)
			(end -0.120396 0.3048)
			(stroke
				(width 0.1)
				(type default)
			)
			(layer "B.Fab")
		)
		(fp_line
			(start -0.12065 -0.3048)
			(end -0.67945 -0.3048)
			(stroke
				(width 0.1)
				(type default)
			)
			(layer "B.Fab")
		)
		(fp_line
			(start -0.12065 -0.2794)
			(end -0.12065 -0.3048)
			(stroke
				(width 0.1)
				(type default)
			)
			(layer "B.Fab")
		)
		(fp_line
			(start -0.120396 0.2794)
			(end 0.12065 0.2794)
			(stroke
				(width 0.1)
				(type default)
			)
			(layer "B.Fab")
		)
		(fp_line
			(start -0.120396 0.3048)
			(end -0.120396 0.2794)
			(stroke
				(width 0.1)
				(type default)
			)
			(layer "B.Fab")
		)
		(fp_line
			(start 0.12065 -0.305054)
			(end 0.12065 -0.2794)
			(stroke
				(width 0.1)
				(type default)
			)
			(layer "B.Fab")
		)
		(fp_line
			(start 0.12065 -0.2794)
			(end -0.12065 -0.2794)
			(stroke
				(width 0.1)
				(type default)
			)
			(layer "B.Fab")
		)
		(fp_line
			(start 0.12065 0.2794)
			(end 0.12065 0.3048)
			(stroke
				(width 0.1)
				(type default)
			)
			(layer "B.Fab")
		)
		(fp_line
			(start 0.12065 0.3048)
			(end 0.67945 0.3048)
			(stroke
				(width 0.1)
				(type default)
			)
			(layer "B.Fab")
		)
		(fp_line
			(start 0.67945 -0.305054)
			(end 0.12065 -0.305054)
			(stroke
				(width 0.1)
				(type default)
			)
			(layer "B.Fab")
		)
		(fp_line
			(start 0.67945 0.3048)
			(end 0.67945 -0.305054)
			(stroke
				(width 0.1)
				(type default)
			)
			(layer "B.Fab")
		)
		(pad "1" smd circle
			(at 0.40005 0 180)
			(size 0 0)
			(layers "B.Cu" "B.Mask" "B.Paste")
			(net "P3V3_SDB_VPHY")
		)
		(pad "2" smd circle
			(at -0.40005 0 180)
			(size 0 0)
			(layers "B.Cu" "B.Mask" "B.Paste")
			(net "GND")
		)
	)
	(footprint ""
		(layer "B.Cu")
		(at 172.424852 -305.399948 -90)
		(property "Reference" "C3145"
			(at 0 0 90)
			(layer "B.SilkS")
			(hide yes)
			(effects
				(font
					(size 1.27 1.27)
				)
				(justify mirror)
			)
		)
		(property "Value" ""
			(at 0 0 90)
			(layer "B.Fab")
			(effects
				(font
					(size 1.27 1.27)
				)
				(justify mirror)
			)
		)
		(duplicate_pad_numbers_are_jumpers no)
		(fp_line
			(start -0.299974 0.150114)
			(end 0.299974 0.150114)
			(stroke
				(width 0.1)
				(type default)
			)
			(layer "B.Fab")
		)
		(fp_line
			(start 0.299974 0.150114)
			(end 0.299974 -0.150114)
			(stroke
				(width 0.1)
				(type default)
			)
			(layer "B.Fab")
		)
		(fp_line
			(start -0.299974 -0.150114)
			(end -0.299974 0.150114)
			(stroke
				(width 0.1)
				(type default)
			)
			(layer "B.Fab")
		)
		(fp_line
			(start 0.299974 -0.150114)
			(end -0.299974 -0.150114)
			(stroke
				(width 0.1)
				(type default)
			)
			(layer "B.Fab")
		)
		(pad "1" smd rect
			(at 0.2667 0 90)
			(size 0.3048 0.381)
			(layers "B.Cu" "B.Mask" "B.Paste")
			(net "P1V25_SERDES_VDDPLL_PEX1")
		)
		(pad "2" smd rect
			(at -0.2667 0 90)
			(size 0.3048 0.381)
			(layers "B.Cu" "B.Mask" "B.Paste")
			(net "GND")
		)
	)
	(footprint ""
		(layer "B.Cu")
		(at 167.675052 -297.79976 90)
		(property "Reference" "C1401"
			(at 0 0 90)
			(layer "B.SilkS")
			(hide yes)
			(effects
				(font
					(size 1.27 1.27)
				)
				(justify mirror)
			)
		)
		(property "Value" ""
			(at 0 0 90)
			(layer "B.Fab")
			(effects
				(font
					(size 1.27 1.27)
				)
				(justify mirror)
			)
		)
		(duplicate_pad_numbers_are_jumpers no)
		(fp_line
			(start 0.299974 -0.150114)
			(end -0.299974 -0.150114)
			(stroke
				(width 0.1)
				(type default)
			)
			(layer "B.Fab")
		)
		(fp_line
			(start -0.299974 -0.150114)
			(end -0.299974 0.150114)
			(stroke
				(width 0.1)
				(type default)
			)
			(layer "B.Fab")
		)
		(fp_line
			(start 0.299974 0.150114)
			(end 0.299974 -0.150114)
			(stroke
				(width 0.1)
				(type default)
			)
			(layer "B.Fab")
		)
		(fp_line
			(start -0.299974 0.150114)
			(end 0.299974 0.150114)
			(stroke
				(width 0.1)
				(type default)
			)
			(layer "B.Fab")
		)
		(pad "1" smd rect
			(at 0.2667 0 270)
			(size 0.3048 0.381)
			(layers "B.Cu" "B.Mask" "B.Paste")
			(net "P0V8_PEX1")
		)
		(pad "2" smd rect
			(at -0.2667 0 270)
			(size 0.3048 0.381)
			(layers "B.Cu" "B.Mask" "B.Paste")
			(net "GND")
		)
	)
	(footprint ""
		(layer "B.Cu")
		(at 406.999948 -290.199826 90)
		(property "Reference" "C1938"
			(at 0 0 90)
			(layer "B.SilkS")
			(hide yes)
			(effects
				(font
					(size 1.27 1.27)
				)
				(justify mirror)
			)
		)
		(property "Value" ""
			(at 0 0 90)
			(layer "B.Fab")
			(effects
				(font
					(size 1.27 1.27)
				)
				(justify mirror)
			)
		)
		(duplicate_pad_numbers_are_jumpers no)
		(fp_line
			(start 0.299974 -0.150114)
			(end -0.299974 -0.150114)
			(stroke
				(width 0.1)
				(type default)
			)
			(layer "B.Fab")
		)
		(fp_line
			(start -0.299974 -0.150114)
			(end -0.299974 0.150114)
			(stroke
				(width 0.1)
				(type default)
			)
			(layer "B.Fab")
		)
		(fp_line
			(start 0.299974 0.150114)
			(end 0.299974 -0.150114)
			(stroke
				(width 0.1)
				(type default)
			)
			(layer "B.Fab")
		)
		(fp_line
			(start -0.299974 0.150114)
			(end 0.299974 0.150114)
			(stroke
				(width 0.1)
				(type default)
			)
			(layer "B.Fab")
		)
		(pad "1" smd rect
			(at 0.2667 0 270)
			(size 0.3048 0.381)
			(layers "B.Cu" "B.Mask" "B.Paste")
			(net "P0V8_SERDES_VDDA_PEX3")
		)
		(pad "2" smd rect
			(at -0.2667 0 270)
			(size 0.3048 0.381)
			(layers "B.Cu" "B.Mask" "B.Paste")
			(net "GND")
		)
	)
	(footprint ""
		(layer "B.Cu")
		(at 106.441494 -293.660068 90)
		(property "Reference" "PC87"
			(at 0 0 90)
			(layer "B.SilkS")
			(hide yes)
			(effects
				(font
					(size 1.27 1.27)
				)
				(justify mirror)
			)
		)
		(property "Value" ""
			(at 0 0 90)
			(layer "B.Fab")
			(effects
				(font
					(size 1.27 1.27)
				)
				(justify mirror)
			)
		)
		(duplicate_pad_numbers_are_jumpers no)
		(fp_line
			(start 4.84378 -2.150618)
			(end 4.53898 -2.150618)
			(stroke
				(width 0.1524)
				(type default)
			)
			(layer "B.SilkS")
		)
		(fp_line
			(start 4.84378 -2.150618)
			(end 4.842256 2.163064)
			(stroke
				(width 0.1524)
				(type default)
			)
			(layer "B.SilkS")
		)
		(fp_line
			(start 4.69138 -2.150618)
			(end 4.692396 2.161032)
			(stroke
				(width 0.1524)
				(type default)
			)
			(layer "B.SilkS")
		)
		(fp_line
			(start 4.53898 -2.150618)
			(end 4.539742 2.152142)
			(stroke
				(width 0.1524)
				(type default)
			)
			(layer "B.SilkS")
		)
		(fp_line
			(start 4.53898 -2.15011)
			(end -4.53898 -2.15011)
			(stroke
				(width 0.1524)
				(type default)
			)
			(layer "B.SilkS")
		)
		(fp_line
			(start -4.53898 -2.15011)
			(end -4.53898 2.15011)
			(stroke
				(width 0.1524)
				(type default)
			)
			(layer "B.SilkS")
		)
		(fp_line
			(start 4.53898 2.15011)
			(end 4.53898 -2.15011)
			(stroke
				(width 0.1524)
				(type default)
			)
			(layer "B.SilkS")
		)
		(fp_line
			(start -4.53898 2.15011)
			(end 4.53898 2.15011)
			(stroke
				(width 0.1524)
				(type default)
			)
			(layer "B.SilkS")
		)
		(fp_line
			(start 4.83108 2.150364)
			(end 4.447794 2.149348)
			(stroke
				(width 0.1524)
				(type default)
			)
			(layer "B.SilkS")
		)
		(fp_line
			(start 3.64998 -2.15011)
			(end -3.64998 -2.15011)
			(stroke
				(width 0.1)
				(type default)
			)
			(layer "B.Fab")
		)
		(fp_line
			(start -3.64998 -2.15011)
			(end -3.64998 2.15011)
			(stroke
				(width 0.1)
				(type default)
			)
			(layer "B.Fab")
		)
		(fp_line
			(start 3.64998 2.15011)
			(end 3.64998 -2.15011)
			(stroke
				(width 0.1)
				(type default)
			)
			(layer "B.Fab")
		)
		(fp_line
			(start -3.64998 2.15011)
			(end 3.64998 2.15011)
			(stroke
				(width 0.1)
				(type default)
			)
			(layer "B.Fab")
		)
		(fp_text user "+"
			(at 6.214872 -0.337058 90)
			(unlocked yes)
			(layer "B.SilkS")
			(effects
				(font
					(size 1.905 1.4224)
					(thickness 0.1524)
				)
				(justify left mirror)
			)
		)
		(fp_text user "-"
			(at -4.313174 -0.094488 90)
			(unlocked yes)
			(layer "B.SilkS")
			(effects
				(font
					(size 1.905 1.4224)
					(thickness 0.1524)
				)
				(justify left mirror)
			)
		)
		(fp_text user "+"
			(at 6.214872 -0.337058 90)
			(unlocked yes)
			(layer "B.Fab")
			(effects
				(font
					(size 1.905 1.4224)
					(thickness 0.1524)
				)
				(justify left mirror)
			)
		)
		(fp_text user "-"
			(at -4.313174 -0.094488 90)
			(unlocked yes)
			(layer "B.Fab")
			(effects
				(font
					(size 1.905 1.4224)
					(thickness 0.1524)
				)
				(justify left mirror)
			)
		)
		(pad "1" smd rect
			(at 3.199892 0 270)
			(size 2.413 2.8194)
			(layers "B.Cu" "B.Mask" "B.Paste")
			(net "P0V8_PEX0")
		)
		(pad "2" smd rect
			(at -3.199892 0 270)
			(size 2.413 2.8194)
			(layers "B.Cu" "B.Mask" "B.Paste")
			(net "GND")
		)
	)
)
